G04 ================== begin FILE IDENTIFICATION RECORD ==================*
G04 Layout Name:  15750-1.brd*
G04 Film Name:    L8*
G04 File Format:  Gerber RS274X*
G04 File Origin:  Cadence Allegro 16.5-S056*
G04 Origin Date:  Fri Dec 30 13:21:41 2016*
G04 *
G04 Layer:  VIA CLASS/BOTTOM*
G04 Layer:  PIN/BOTTOM*
G04 Layer:  ETCH/BOTTOM*
G04 Layer:  DRAWING FORMAT/LAYER_L8*
G04 Layer:  DRAWING FORMAT/LAYER_PCB_STORY*
G04 *
G04 Offset:    (0.00 0.00)*
G04 Mirror:    No*
G04 Mode:      Positive*
G04 Rotation:  0*
G04 FullContactRelief:  No*
G04 UndefLineWidth:     6.00*
G04 ================== end FILE IDENTIFICATION RECORD ====================*
%FSLAX35Y35*MOIN*%
%IR0*IPPOS*OFA0.00000B0.00000*MIA0B0*SFA1.00000B1.00000*%
%AMMACRO19*
4,1,40,.011,.007,
.011,-.007,
.010939,-.007695,
.010759,-.008368,
.010464,-.009,
.010064,-.009571,
.009571,-.010064,
.009,-.010464,
.008368,-.010759,
.007695,-.010939,
.007,-.011,
-.007,-.011,
-.007695,-.010939,
-.008368,-.010759,
-.009,-.010464,
-.009571,-.010064,
-.010064,-.009571,
-.010464,-.009,
-.010759,-.008368,
-.010939,-.007695,
-.011,-.007,
-.011,.007,
-.010939,.007695,
-.010759,.008368,
-.010464,.009,
-.010064,.009571,
-.009571,.010064,
-.009,.010464,
-.008368,.010759,
-.007695,.010939,
-.007,.011,
.007,.011,
.007695,.010939,
.008368,.010759,
.009,.010464,
.009571,.010064,
.010064,.009571,
.010464,.009,
.010759,.008368,
.010939,.007695,
.011,.007,
0.0*
%
%ADD19MACRO19*%
%AMMACRO26*
4,1,40,.013,-.017,
-.013,-.017,
-.013695,-.016939,
-.014368,-.016759,
-.015,-.016464,
-.015571,-.016064,
-.016064,-.015571,
-.016464,-.015,
-.016759,-.014368,
-.016939,-.013695,
-.017,-.013,
-.017,.013,
-.016939,.013695,
-.016759,.014368,
-.016464,.015,
-.016064,.015571,
-.015571,.016064,
-.015,.016464,
-.014368,.016759,
-.013695,.016939,
-.013,.017,
.013,.017,
.013695,.016939,
.014368,.016759,
.015,.016464,
.015571,.016064,
.016064,.015571,
.016464,.015,
.016759,.014368,
.016939,.013695,
.017,.013,
.017,-.013,
.016939,-.013695,
.016759,-.014368,
.016464,-.015,
.016064,-.015571,
.015571,-.016064,
.015,-.016464,
.014368,-.016759,
.013695,-.016939,
.013,-.017,
0.0*
%
%ADD26MACRO26*%
%ADD10C,.01*%
%ADD15C,.02*%
%ADD13C,.022*%
%ADD12C,.04*%
%ADD14C,.028*%
%ADD35C,.056*%
%AMMACRO20*
4,1,40,.007,-.011,
-.007,-.011,
-.007695,-.010939,
-.008368,-.010759,
-.009,-.010464,
-.009571,-.010064,
-.010064,-.009571,
-.010464,-.009,
-.010759,-.008368,
-.010939,-.007695,
-.011,-.007,
-.011,.007,
-.010939,.007695,
-.010759,.008368,
-.010464,.009,
-.010064,.009571,
-.009571,.010064,
-.009,.010464,
-.008368,.010759,
-.007695,.010939,
-.007,.011,
.007,.011,
.007695,.010939,
.008368,.010759,
.009,.010464,
.009571,.010064,
.010064,.009571,
.010464,.009,
.010759,.008368,
.010939,.007695,
.011,.007,
.011,-.007,
.010939,-.007695,
.010759,-.008368,
.010464,-.009,
.010064,-.009571,
.009571,-.010064,
.009,-.010464,
.008368,-.010759,
.007695,-.010939,
.007,-.011,
0.0*
%
%ADD20MACRO20*%
%AMMACRO16*
4,1,40,-.011,-.007,
-.011,.007,
-.010939,.007695,
-.010759,.008368,
-.010464,.009,
-.010064,.009571,
-.009571,.010064,
-.009,.010464,
-.008368,.010759,
-.007695,.010939,
-.007,.011,
.007,.011,
.007695,.010939,
.008368,.010759,
.009,.010464,
.009571,.010064,
.010064,.009571,
.010464,.009,
.010759,.008368,
.010939,.007695,
.011,.007,
.011,-.007,
.010939,-.007695,
.010759,-.008368,
.010464,-.009,
.010064,-.009571,
.009571,-.010064,
.009,-.010464,
.008368,-.010759,
.007695,-.010939,
.007,-.011,
-.007,-.011,
-.007695,-.010939,
-.008368,-.010759,
-.009,-.010464,
-.009571,-.010064,
-.010064,-.009571,
-.010464,-.009,
-.010759,-.008368,
-.010939,-.007695,
-.011,-.007,
0.0*
%
%ADD16MACRO16*%
%AMMACRO28*
4,1,40,-.008,.012,
.008,.012,
.008695,.011939,
.009368,.011759,
.01,.011464,
.010571,.011064,
.011064,.010571,
.011464,.01,
.011759,.009368,
.011939,.008695,
.012,.008,
.012,-.008,
.011939,-.008695,
.011759,-.009368,
.011464,-.01,
.011064,-.010571,
.010571,-.011064,
.01,-.011464,
.009368,-.011759,
.008695,-.011939,
.008,-.012,
-.008,-.012,
-.008695,-.011939,
-.009368,-.011759,
-.01,-.011464,
-.010571,-.011064,
-.011064,-.010571,
-.011464,-.01,
-.011759,-.009368,
-.011939,-.008695,
-.012,-.008,
-.012,.008,
-.011939,.008695,
-.011759,.009368,
-.011464,.01,
-.011064,.010571,
-.010571,.011064,
-.01,.011464,
-.009368,.011759,
-.008695,.011939,
-.008,.012,
0.0*
%
%ADD28MACRO28*%
%AMMACRO29*
4,1,40,-.013,.017,
.013,.017,
.013695,.016939,
.014368,.016759,
.015,.016464,
.015571,.016064,
.016064,.015571,
.016464,.015,
.016759,.014368,
.016939,.013695,
.017,.013,
.017,-.013,
.016939,-.013695,
.016759,-.014368,
.016464,-.015,
.016064,-.015571,
.015571,-.016064,
.015,-.016464,
.014368,-.016759,
.013695,-.016939,
.013,-.017,
-.013,-.017,
-.013695,-.016939,
-.014368,-.016759,
-.015,-.016464,
-.015571,-.016064,
-.016064,-.015571,
-.016464,-.015,
-.016759,-.014368,
-.016939,-.013695,
-.017,-.013,
-.017,.013,
-.016939,.013695,
-.016759,.014368,
-.016464,.015,
-.016064,.015571,
-.015571,.016064,
-.015,.016464,
-.014368,.016759,
-.013695,.016939,
-.013,.017,
0.0*
%
%ADD29MACRO29*%
%AMMACRO21*
4,1,40,.007,-.011,
-.007,-.011,
-.007695,-.010939,
-.008368,-.010759,
-.009,-.010464,
-.009571,-.010064,
-.010064,-.009571,
-.010464,-.009,
-.010759,-.008368,
-.010939,-.007695,
-.011,-.007,
-.011,.007,
-.010939,.007695,
-.010759,.008368,
-.010464,.009,
-.010064,.009571,
-.009571,.010064,
-.009,.010464,
-.008368,.010759,
-.007695,.010939,
-.007,.011,
.007,.011,
.007695,.010939,
.008368,.010759,
.009,.010464,
.009571,.010064,
.010064,.009571,
.010464,.009,
.010759,.008368,
.010939,.007695,
.011,.007,
.011,-.007,
.010939,-.007695,
.010759,-.008368,
.010464,-.009,
.010064,-.009571,
.009571,-.010064,
.009,-.010464,
.008368,-.010759,
.007695,-.010939,
.007,-.011,
0.0*
%
%ADD21MACRO21*%
%AMMACRO17*
4,1,40,-.011,-.007,
-.011,.007,
-.010939,.007695,
-.010759,.008368,
-.010464,.009,
-.010064,.009571,
-.009571,.010064,
-.009,.010464,
-.008368,.010759,
-.007695,.010939,
-.007,.011,
.007,.011,
.007695,.010939,
.008368,.010759,
.009,.010464,
.009571,.010064,
.010064,.009571,
.010464,.009,
.010759,.008368,
.010939,.007695,
.011,.007,
.011,-.007,
.010939,-.007695,
.010759,-.008368,
.010464,-.009,
.010064,-.009571,
.009571,-.010064,
.009,-.010464,
.008368,-.010759,
.007695,-.010939,
.007,-.011,
-.007,-.011,
-.007695,-.010939,
-.008368,-.010759,
-.009,-.010464,
-.009571,-.010064,
-.010064,-.009571,
-.010464,-.009,
-.010759,-.008368,
-.010939,-.007695,
-.011,-.007,
0.0*
%
%ADD17MACRO17*%
%AMMACRO27*
4,1,40,-.008,.012,
.008,.012,
.008695,.011939,
.009368,.011759,
.01,.011464,
.010571,.011064,
.011064,.010571,
.011464,.01,
.011759,.009368,
.011939,.008695,
.012,.008,
.012,-.008,
.011939,-.008695,
.011759,-.009368,
.011464,-.01,
.011064,-.010571,
.010571,-.011064,
.01,-.011464,
.009368,-.011759,
.008695,-.011939,
.008,-.012,
-.008,-.012,
-.008695,-.011939,
-.009368,-.011759,
-.01,-.011464,
-.010571,-.011064,
-.011064,-.010571,
-.011464,-.01,
-.011759,-.009368,
-.011939,-.008695,
-.012,-.008,
-.012,.008,
-.011939,.008695,
-.011759,.009368,
-.011464,.01,
-.011064,.010571,
-.010571,.011064,
-.01,.011464,
-.009368,.011759,
-.008695,.011939,
-.008,.012,
0.0*
%
%ADD27MACRO27*%
%AMMACRO30*
4,1,40,-.013,.017,
.013,.017,
.013695,.016939,
.014368,.016759,
.015,.016464,
.015571,.016064,
.016064,.015571,
.016464,.015,
.016759,.014368,
.016939,.013695,
.017,.013,
.017,-.013,
.016939,-.013695,
.016759,-.014368,
.016464,-.015,
.016064,-.015571,
.015571,-.016064,
.015,-.016464,
.014368,-.016759,
.013695,-.016939,
.013,-.017,
-.013,-.017,
-.013695,-.016939,
-.014368,-.016759,
-.015,-.016464,
-.015571,-.016064,
-.016064,-.015571,
-.016464,-.015,
-.016759,-.014368,
-.016939,-.013695,
-.017,-.013,
-.017,.013,
-.016939,.013695,
-.016759,.014368,
-.016464,.015,
-.016064,.015571,
-.015571,.016064,
-.015,.016464,
-.014368,.016759,
-.013695,.016939,
-.013,.017,
0.0*
%
%ADD30MACRO30*%
%ADD38R,.157X.15*%
%ADD36R,.069X.02*%
%ADD37R,.073X.035*%
%ADD11C,.315*%
%ADD31R,.045X.055*%
%ADD33R,.016X.048*%
%ADD24R,.055X.045*%
%AMMACRO32*
4,1,40,.012,.008,
.012,-.008,
.011939,-.008695,
.011759,-.009368,
.011464,-.01,
.011064,-.010571,
.010571,-.011064,
.01,-.011464,
.009368,-.011759,
.008695,-.011939,
.008,-.012,
-.008,-.012,
-.008695,-.011939,
-.009368,-.011759,
-.01,-.011464,
-.010571,-.011064,
-.011064,-.010571,
-.011464,-.01,
-.011759,-.009368,
-.011939,-.008695,
-.012,-.008,
-.012,.008,
-.011939,.008695,
-.011759,.009368,
-.011464,.01,
-.011064,.010571,
-.010571,.011064,
-.01,.011464,
-.009368,.011759,
-.008695,.011939,
-.008,.012,
.008,.012,
.008695,.011939,
.009368,.011759,
.01,.011464,
.010571,.011064,
.011064,.010571,
.011464,.01,
.011759,.009368,
.011939,.008695,
.012,.008,
0.0*
%
%ADD32MACRO32*%
%AMMACRO22*
4,1,40,-.007,.011,
.007,.011,
.007695,.010939,
.008368,.010759,
.009,.010464,
.009571,.010064,
.010064,.009571,
.010464,.009,
.010759,.008368,
.010939,.007695,
.011,.007,
.011,-.007,
.010939,-.007695,
.010759,-.008368,
.010464,-.009,
.010064,-.009571,
.009571,-.010064,
.009,-.010464,
.008368,-.010759,
.007695,-.010939,
.007,-.011,
-.007,-.011,
-.007695,-.010939,
-.008368,-.010759,
-.009,-.010464,
-.009571,-.010064,
-.010064,-.009571,
-.010464,-.009,
-.010759,-.008368,
-.010939,-.007695,
-.011,-.007,
-.011,.007,
-.010939,.007695,
-.010759,.008368,
-.010464,.009,
-.010064,.009571,
-.009571,.010064,
-.009,.010464,
-.008368,.010759,
-.007695,.010939,
-.007,.011,
0.0*
%
%ADD22MACRO22*%
%AMMACRO18*
4,1,40,.011,.007,
.011,-.007,
.010939,-.007695,
.010759,-.008368,
.010464,-.009,
.010064,-.009571,
.009571,-.010064,
.009,-.010464,
.008368,-.010759,
.007695,-.010939,
.007,-.011,
-.007,-.011,
-.007695,-.010939,
-.008368,-.010759,
-.009,-.010464,
-.009571,-.010064,
-.010064,-.009571,
-.010464,-.009,
-.010759,-.008368,
-.010939,-.007695,
-.011,-.007,
-.011,.007,
-.010939,.007695,
-.010759,.008368,
-.010464,.009,
-.010064,.009571,
-.009571,.010064,
-.009,.010464,
-.008368,.010759,
-.007695,.010939,
-.007,.011,
.007,.011,
.007695,.010939,
.008368,.010759,
.009,.010464,
.009571,.010064,
.010064,.009571,
.010464,.009,
.010759,.008368,
.010939,.007695,
.011,.007,
0.0*
%
%ADD18MACRO18*%
%AMMACRO25*
4,1,40,.013,-.017,
-.013,-.017,
-.013695,-.016939,
-.014368,-.016759,
-.015,-.016464,
-.015571,-.016064,
-.016064,-.015571,
-.016464,-.015,
-.016759,-.014368,
-.016939,-.013695,
-.017,-.013,
-.017,.013,
-.016939,.013695,
-.016759,.014368,
-.016464,.015,
-.016064,.015571,
-.015571,.016064,
-.015,.016464,
-.014368,.016759,
-.013695,.016939,
-.013,.017,
.013,.017,
.013695,.016939,
.014368,.016759,
.015,.016464,
.015571,.016064,
.016064,.015571,
.016464,.015,
.016759,.014368,
.016939,.013695,
.017,.013,
.017,-.013,
.016939,-.013695,
.016759,-.014368,
.016464,-.015,
.016064,-.015571,
.015571,-.016064,
.015,-.016464,
.014368,-.016759,
.013695,-.016939,
.013,-.017,
0.0*
%
%ADD25MACRO25*%
%AMMACRO34*
4,1,40,.012,.008,
.012,-.008,
.011939,-.008695,
.011759,-.009368,
.011464,-.01,
.011064,-.010571,
.010571,-.011064,
.01,-.011464,
.009368,-.011759,
.008695,-.011939,
.008,-.012,
-.008,-.012,
-.008695,-.011939,
-.009368,-.011759,
-.01,-.011464,
-.010571,-.011064,
-.011064,-.010571,
-.011464,-.01,
-.011759,-.009368,
-.011939,-.008695,
-.012,-.008,
-.012,.008,
-.011939,.008695,
-.011759,.009368,
-.011464,.01,
-.011064,.010571,
-.010571,.011064,
-.01,.011464,
-.009368,.011759,
-.008695,.011939,
-.008,.012,
.008,.012,
.008695,.011939,
.009368,.011759,
.01,.011464,
.010571,.011064,
.011064,.010571,
.011464,.01,
.011759,.009368,
.011939,.008695,
.012,.008,
0.0*
%
%ADD34MACRO34*%
%AMMACRO23*
4,1,40,-.007,.011,
.007,.011,
.007695,.010939,
.008368,.010759,
.009,.010464,
.009571,.010064,
.010064,.009571,
.010464,.009,
.010759,.008368,
.010939,.007695,
.011,.007,
.011,-.007,
.010939,-.007695,
.010759,-.008368,
.010464,-.009,
.010064,-.009571,
.009571,-.010064,
.009,-.010464,
.008368,-.010759,
.007695,-.010939,
.007,-.011,
-.007,-.011,
-.007695,-.010939,
-.008368,-.010759,
-.009,-.010464,
-.009571,-.010064,
-.010064,-.009571,
-.010464,-.009,
-.010759,-.008368,
-.010939,-.007695,
-.011,-.007,
-.011,.007,
-.010939,.007695,
-.010759,.008368,
-.010464,.009,
-.010064,.009571,
-.009571,.010064,
-.009,.010464,
-.008368,.010759,
-.007695,.010939,
-.007,.011,
0.0*
%
%ADD23MACRO23*%
%ADD39C,.012*%
%ADD40C,.016*%
%ADD41C,.006*%
%ADD42C,.00538*%
%ADD43C,.00475*%
%ADD48C,.08004*%
%ADD44C,.09204*%
%ADD45C,.06804*%
%ADD50C,.08704*%
%ADD46C,.08904*%
%ADD49R,.01X.01*%
%ADD47C,.33904*%
G75*
%LPD*%
G75*
G36*
G01X269000Y169500D02*
X268692Y169808D01*
G02X268686Y170368I283J283D01*
G03X268000Y176983I-3135J3018D01*
G01Y182464D01*
X268952Y183417D01*
Y214825D01*
X258002Y225776D01*
Y259417D01*
X251466Y265952D01*
X232854D01*
X219356Y279450D01*
X216050D01*
X216000Y279500D01*
X139778D01*
X132000Y287278D01*
Y295500D01*
X132500Y296000D01*
X151000D01*
X162000Y285000D01*
X200500D01*
X204500Y289000D01*
X220671D01*
G02X221003Y288376I0J-400D01*
G03X224819I1908J-1287D01*
G02X225151Y289000I332J224D01*
G01X277500D01*
X278500Y290000D01*
Y314500D01*
X270000Y323000D01*
Y350000D01*
X264000Y356000D01*
X124500D01*
X124000Y355500D01*
X62500D01*
X50000Y343000D01*
Y299000D01*
X78000Y271000D01*
X112000D01*
X114000Y269000D01*
Y268500D01*
X113500Y268000D01*
X7000D01*
X2000Y273000D01*
Y356000D01*
X7500Y361500D01*
X279404D01*
G02X279588Y360745I0J-400D01*
G03X295226I7819J-15041D01*
G02X295410Y361500I184J355D01*
G01X341500D01*
X347500Y355500D01*
Y279500D01*
X347000Y279000D01*
X338000D01*
X335500Y276500D01*
Y218000D01*
X338000Y215500D01*
X347000D01*
X347500Y215000D01*
Y196500D01*
X347000Y196000D01*
X319500D01*
X317000Y193500D01*
Y172000D01*
X316288Y171288D01*
X316242D01*
Y171242D01*
X314500Y169500D01*
X293210D01*
X293194Y169683D01*
G03X289595Y171195I-2194J-183D01*
G02X288940Y171503I-255J308D01*
G01Y184332D01*
G03Y188668I-1440J2168D01*
G01Y193650D01*
G02X289641Y193913I400J0D01*
G03X293327Y196220I1659J1448D01*
G01X293312Y196258D01*
Y197664D01*
X293327Y197702D01*
G03X289641Y200009I-2027J859D01*
G02X288940Y200272I-301J263D01*
G01Y240937D01*
X291563Y243560D01*
X299915D01*
G03Y246440I1796J1440D01*
G01X290371D01*
X286060Y242129D01*
Y224191D01*
G02X285378Y223908I-400J0D01*
G01X272802Y236484D01*
Y237500D01*
G03X271200Y239102I-1602J0D01*
G01X269800D01*
G03X269319Y239028I0J-1602D01*
G02X268800Y239427I-120J381D01*
G03X268802Y239500I-1600J80D01*
G01Y240900D01*
G03X268401Y241959I-1602J-1D01*
G02X268405Y242228I150J132D01*
G03X264112Y242967I-1905J1772D01*
G02X263630Y242425I-367J-159D01*
G03X263702Y238228I-630J-2110D01*
G02X264223Y237779I127J-379D01*
G03X264198Y237500I1577J-282D01*
G01Y236100D01*
G03X265800Y234498I1602J0D01*
G01X267200D01*
G03X268240Y234882I-1J1602D01*
G02X268760I260J-304D01*
G03X269800Y234498I1041J1218D01*
G01X270716D01*
X283222Y221992D01*
Y172168D01*
G03X282061Y169913I1440J-2168D01*
G02X281662Y169500I-400J-13D01*
G01X269000D01*
G37*
G36*
G01X249500Y300500D02*
X249000Y301000D01*
Y307500D01*
X264000Y322500D01*
Y347500D01*
X261500Y350000D01*
X87000D01*
X79500Y342500D01*
X75000D01*
X71416Y338916D01*
X71367Y338902D01*
G03X69787Y337322I633J-2213D01*
G01X69773Y337273D01*
X61000Y328500D01*
Y309000D01*
X60500Y308500D01*
X55500D01*
X55000Y309000D01*
Y331500D01*
X77798Y354298D01*
X124498D01*
X124998Y354798D01*
X263202D01*
X268500Y349500D01*
Y347033D01*
G03Y344375I1755J-1329D01*
G01Y318000D01*
X251000Y300500D01*
X249500D01*
G37*
G36*
G01X133500Y298000D02*
X133000Y298500D01*
Y315000D01*
X133500Y315500D01*
X145000D01*
X145500Y315000D01*
Y312000D01*
X144000Y310500D01*
Y298500D01*
X143500Y298000D01*
X133500D01*
G37*
G36*
G01X173090Y317500D02*
X136500D01*
X136000Y318000D01*
Y332000D01*
X136500Y332500D01*
X178311D01*
X178811Y332000D01*
Y318000D01*
X178311Y317500D01*
X174532D01*
X174506Y317507D01*
G03X173116I-695J-2507D01*
G01X173090Y317500D01*
G37*
G36*
G01X151500Y302500D02*
X151000Y302000D01*
X146000D01*
X145500Y302500D01*
Y308500D01*
X146000Y309000D01*
X151000D01*
X151500Y308500D01*
Y302500D01*
G37*
G36*
G01X245176Y2000D02*
G02X244988Y2753I0J400D01*
G03X229038I-7975J14959D01*
G02X228850Y2000I-188J-353D01*
G01X223000D01*
X218000Y7000D01*
Y124000D01*
X218500Y124500D01*
X219081D01*
X227500Y116081D01*
Y95500D01*
X229000Y94000D01*
X238000D01*
X249409Y82591D01*
X249403Y82501D01*
G03X252163Y79741I2597J-163D01*
G01X252253Y79747D01*
X252500Y79500D01*
X252802D01*
X253542Y78760D01*
X262458D01*
X262838Y79140D01*
X262925Y79137D01*
G03X264213Y79500I75J2201D01*
G01X274000D01*
X291000Y62500D01*
Y43000D01*
X293000Y41000D01*
X316500D01*
X317000Y40500D01*
Y23500D01*
X319500Y21000D01*
X346500D01*
X347000Y20500D01*
Y2500D01*
X346501Y2001D01*
X252500D01*
X252499Y2000D01*
X245176D01*
G37*
G36*
G01X237000Y133000D02*
X229000D01*
X228500Y133500D01*
Y143500D01*
X229000Y144000D01*
X237000D01*
X237500Y143500D01*
Y133500D01*
X237000Y133000D01*
G37*
G36*
G01Y174000D02*
X229000D01*
X228500Y174500D01*
Y184500D01*
X229000Y185000D01*
X237000D01*
X237500Y184500D01*
Y174500D01*
X237000Y174000D01*
G37*
G36*
G01Y241500D02*
X229000D01*
X228500Y242000D01*
Y252000D01*
X229000Y252500D01*
X237000D01*
X237500Y252000D01*
Y242000D01*
X237000Y241500D01*
G37*
G36*
G01X252000Y122500D02*
X240000D01*
X239500Y123000D01*
Y143500D01*
X240000Y144000D01*
X251714D01*
X252500Y143214D01*
Y123000D01*
X252000Y122500D01*
G37*
G36*
G01X252500Y174500D02*
X252000Y174000D01*
X240000D01*
X239500Y174500D01*
Y186000D01*
X240000Y186500D01*
X252000D01*
X252500Y186000D01*
Y174500D01*
G37*
G36*
G01Y231500D02*
X252000Y231000D01*
X240000D01*
X239500Y231500D01*
Y252000D01*
X240000Y252500D01*
X252000D01*
X252500Y252000D01*
Y231500D01*
G37*
G36*
G01X314000Y44000D02*
X294500D01*
X294000Y44500D01*
Y58000D01*
X294500Y58500D01*
X305464D01*
Y58190D01*
X314309D01*
X314500Y58000D01*
Y44500D01*
X314000Y44000D01*
G37*
%LPC*%
G75*
G36*
G01X277512Y222821D02*
Y218283D01*
X277505Y218195D01*
G02X272688Y218372I-2405J177D01*
G01Y222812D01*
G02X277512Y222821I2412J-1D01*
G37*
G36*
G01X275512Y211010D02*
Y206472D01*
X275505Y206384D01*
G02X270688Y206561I-2405J177D01*
G01Y211001D01*
G02X275512Y211010I2412J-1D01*
G37*
G36*
G01X254000Y62500D02*
X253500Y62000D01*
X238000D01*
X237500Y62500D01*
Y77000D01*
X238000Y77500D01*
X239301D01*
X239502Y77702D01*
X252498D01*
X252699Y77500D01*
X253500D01*
X254000Y77000D01*
Y62500D01*
G37*
G54D48*
X302000Y290500D03*
Y300500D03*
Y310500D03*
G54D44*
X22401Y341025D03*
X316610D03*
X291000Y22500D03*
G54D45*
X265551Y252126D03*
G54D50*
X311614Y31870D03*
X265551Y64724D03*
G54D46*
X311614Y185414D03*
G54D49*
X271600Y241300D03*
X141811Y311800D03*
G54D47*
X25596Y316176D03*
%LPD*%
G75*
G36*
G01X252000Y63500D02*
X240000D01*
X239500Y64000D01*
Y76000D01*
X240000Y76500D01*
X252000D01*
X252500Y76000D01*
Y64000D01*
X252000Y63500D01*
G37*
G54D10*
G01X202911Y296500D02*
X197111Y290700D01*
X164611D01*
X162311Y293000D01*
G01X169811Y309500D02*
X167311D01*
X165811Y308000D01*
G01X168311Y301750D02*
Y305500D01*
X165811Y308000D01*
G01X172311Y305500D02*
X172811Y306000D01*
Y314000D01*
X173811Y315000D01*
G01X172311Y301750D02*
Y305500D01*
G01X176311Y301750D02*
Y305357D01*
X176168Y305500D01*
G01D02*
Y307857D01*
X177811Y309500D01*
G01X195561Y304250D02*
X199811D01*
G01D02*
Y307000D01*
X200811Y308000D01*
G01Y311000D02*
X204250D01*
X205750Y309500D01*
G01D02*
Y299339D01*
X202911Y296500D01*
G01X200811Y317000D02*
X197061D01*
G01X218000Y292000D02*
X228500D01*
X242500Y306000D01*
G01X218311Y325000D02*
Y307750D01*
G01X215811Y300000D02*
Y301750D01*
X218311Y304250D01*
G01D02*
X222311D01*
G01Y307750D02*
Y325000D01*
X26087Y-114844D03*
X26435Y373984D03*
X175335Y62719D03*
Y189062D03*
X265551Y64724D03*
Y143464D03*
Y173386D03*
Y252126D03*
X311614Y31870D03*
Y185414D03*
X547104Y69007D03*
Y195351D03*
X696192Y373984D03*
G54D11*
X25596Y316176D03*
X237013Y17712D03*
X287407Y345704D03*
G54D20*
X96800Y317000D03*
Y321000D03*
X193611Y317000D03*
X254800Y96500D03*
Y205000D03*
X271300Y131500D03*
Y135500D03*
X255300Y160500D03*
G54D30*
X208200Y320000D03*
G54D21*
X100200Y317000D03*
Y321000D03*
X197011Y317000D03*
X258200Y96500D03*
X258700Y160500D03*
X258200Y205000D03*
X274700Y131500D03*
Y135500D03*
G54D12*
X22401Y341025D03*
X291000Y22500D03*
X316610Y341025D03*
G54D40*
G01X270940Y155750D02*
X269940Y156750D01*
X264500D01*
G54D22*
X123200Y293000D03*
X209200Y309500D03*
X248700Y156500D03*
Y152500D03*
X258200Y88500D03*
Y197000D03*
G54D31*
X234700Y71000D03*
Y138500D03*
Y179500D03*
Y247000D03*
X242300Y71000D03*
Y138500D03*
Y179500D03*
Y247000D03*
G54D13*
X10000Y330000D03*
Y345000D03*
Y360000D03*
X40000Y270000D03*
Y285000D03*
Y300000D03*
Y330000D03*
Y345000D03*
X25000Y360000D03*
X40000D03*
X55000Y270000D03*
Y285000D03*
X52500Y325189D03*
Y331189D03*
X55000Y360000D03*
X70000Y270000D03*
X59500Y294189D03*
X72000Y286000D03*
Y290000D03*
X58000Y310689D03*
X64500Y309589D03*
X59500Y299939D03*
X71500Y315689D03*
X67900D03*
X72000Y336689D03*
X70000Y360000D03*
X85000Y270000D03*
X89000Y295189D03*
Y291189D03*
Y287189D03*
Y283189D03*
Y303689D03*
Y299689D03*
X75100Y315689D03*
X79000Y344000D03*
X89000Y329189D03*
Y333189D03*
X79000Y348000D03*
X85000Y360000D03*
X100000Y270000D03*
Y360000D03*
X115000D03*
X138500Y299500D03*
X134500Y307500D03*
X138500Y303500D03*
Y307500D03*
X137500Y324500D03*
X138000Y341500D03*
X130000Y360000D03*
X138000Y345500D03*
X142500Y299500D03*
Y303500D03*
Y307500D03*
X146500Y303500D03*
X150500D03*
X146500Y307500D03*
X150500D03*
X155000Y301350D03*
X141811Y324500D03*
X145811D03*
X153811D03*
X149811D03*
Y341500D03*
X141811D03*
X145811D03*
X153811D03*
X145000Y360000D03*
X149811Y345500D03*
X141811D03*
X145811D03*
X153811D03*
X162311Y293000D03*
X164811Y304000D03*
X160811Y310000D03*
X169811Y309500D03*
X172311Y305500D03*
X157811Y324500D03*
X161811D03*
X169811D03*
X165811D03*
X169811Y313500D03*
X165811Y341500D03*
X157811D03*
X161811D03*
X169811D03*
X160000Y360000D03*
X165811Y345500D03*
X169811D03*
X157811D03*
X161811D03*
X176311Y294000D03*
X185811Y304200D03*
Y310500D03*
X181811D03*
X181061Y297750D03*
X176168Y305500D03*
X181811Y318500D03*
X185811Y314500D03*
Y326500D03*
Y322500D03*
Y318500D03*
X181811Y326500D03*
Y322500D03*
Y314500D03*
X184500Y334000D03*
Y338000D03*
X175000Y360000D03*
X189811Y310500D03*
X195811Y296000D03*
X200811Y308000D03*
Y311000D03*
X189811Y318500D03*
Y322500D03*
Y326500D03*
Y314500D03*
X200811Y317000D03*
Y314000D03*
X190000Y360000D03*
X205000D03*
X218000Y292000D03*
X215811Y300000D03*
X222311Y325000D03*
X218311D03*
X220000Y360000D03*
X225000Y35000D03*
Y50000D03*
Y80000D03*
Y65000D03*
X230000Y75000D03*
Y67000D03*
Y71000D03*
X225000Y95000D03*
X230000Y96500D03*
X225000Y110000D03*
X230000Y126000D03*
Y130000D03*
Y122000D03*
Y138500D03*
Y142500D03*
Y134500D03*
Y175500D03*
Y179500D03*
Y183500D03*
X225000Y205000D03*
X230000Y243000D03*
Y234500D03*
Y238500D03*
Y230500D03*
Y247000D03*
Y251000D03*
X222911Y287089D03*
X237500Y340000D03*
Y344000D03*
Y336000D03*
X235000Y360000D03*
X255000Y5000D03*
Y35000D03*
X247000Y68838D03*
Y72838D03*
X251000Y68838D03*
Y72838D03*
X247000Y123838D03*
X251000D03*
X247000Y127838D03*
X251000D03*
X247000Y136338D03*
Y140838D03*
X251000D03*
Y136338D03*
Y177500D03*
X247000D03*
X251000Y181500D03*
X247000D03*
X251000Y245000D03*
X247000D03*
X251000Y236500D03*
X247000D03*
X251000Y232500D03*
X247000D03*
X251000Y249500D03*
X247000D03*
X249000Y260000D03*
X242500Y294000D03*
X246500D03*
X250500D03*
X242500Y306000D03*
Y302000D03*
Y298000D03*
X246500Y306000D03*
Y302000D03*
Y298000D03*
X250500D03*
Y302000D03*
Y306000D03*
X241500Y336000D03*
Y344000D03*
Y340000D03*
X250000Y360000D03*
X270000Y5000D03*
Y35000D03*
X262920Y131653D03*
X265000Y270000D03*
Y285000D03*
X271500Y294000D03*
X267500D03*
X271500Y306000D03*
Y302000D03*
Y298000D03*
X267500D03*
Y302000D03*
Y306000D03*
X260500Y340000D03*
Y344000D03*
Y336000D03*
X256500D03*
Y344000D03*
Y340000D03*
X265000Y360000D03*
X282500Y5000D03*
X272500Y20000D03*
X285000Y32500D03*
X275500Y63346D03*
X280000Y71614D03*
Y67677D03*
X273000Y92283D03*
X280169Y126732D03*
Y120826D03*
X275768Y144842D03*
X280169Y138543D03*
Y132637D03*
X280000Y176339D03*
X275500Y172008D03*
X280000Y180276D03*
X280169Y247205D03*
X275768Y253504D03*
X280000Y270000D03*
X275500Y294000D03*
X280000Y285000D03*
X275500Y298000D03*
Y302000D03*
Y306000D03*
X280000Y300000D03*
Y315000D03*
X295000Y5000D03*
X300000Y20000D03*
X299500Y46000D03*
X303500D03*
X300000Y35000D03*
X296500Y61000D03*
X300500D03*
X301500Y49000D03*
X297500D03*
X295500Y52000D03*
X299500D03*
X304565Y61142D03*
Y96142D03*
X304500Y92000D03*
X291500Y97204D03*
X291550Y91299D03*
X291500Y85393D03*
X295500Y110000D03*
Y100000D03*
X291500Y109960D03*
Y101960D03*
X295311Y127600D03*
X304500Y123820D03*
X291500Y114921D03*
X304565Y141142D03*
X295500Y208461D03*
X291500Y210961D03*
Y205866D03*
Y218461D03*
Y223583D03*
X301711Y245000D03*
X291500Y241299D03*
Y229488D03*
Y235394D03*
X295000Y270000D03*
Y285000D03*
Y300000D03*
Y315000D03*
X315000Y5000D03*
Y20000D03*
Y40000D03*
X313000Y179500D03*
X310000Y225000D03*
Y240000D03*
Y255000D03*
Y270000D03*
Y285000D03*
Y300000D03*
Y315000D03*
Y330000D03*
Y360000D03*
Y345000D03*
X324302Y203977D03*
X325000Y225000D03*
Y240000D03*
Y255000D03*
Y270000D03*
Y285000D03*
Y300000D03*
Y315000D03*
Y330000D03*
Y360000D03*
Y345000D03*
X345000Y5000D03*
Y20000D03*
X340000Y285000D03*
Y300000D03*
Y315000D03*
Y330000D03*
Y360000D03*
Y345000D03*
G54D41*
G01X-148956Y-251503D02*
Y-269003D01*
X-140222D01*
G01X-127089Y-257337D02*
Y-269003D01*
G01Y-252670D02*
X-127526Y-252378D01*
Y-251795D01*
X-127089Y-251503D01*
X-126652Y-251795D01*
Y-252378D01*
X-127089Y-252670D01*
G01X-112646Y-273378D02*
X-111117Y-274545D01*
X-109371Y-274836D01*
X-107843Y-274545D01*
X-106532Y-273087D01*
X-105659Y-271045D01*
Y-257337D01*
G01Y-259670D02*
X-106532Y-258503D01*
X-107843Y-257628D01*
X-109371Y-257337D01*
X-111117Y-257920D01*
X-112209Y-259086D01*
X-113083Y-261128D01*
X-113519Y-263170D01*
X-113301Y-264920D01*
X-112427Y-266962D01*
X-111117Y-268420D01*
X-109371Y-269003D01*
X-108061Y-268711D01*
X-106532Y-267545D01*
X-105659Y-266379D01*
G01X-95801Y-269003D02*
Y-251503D01*
G01Y-259961D02*
X-94709Y-258503D01*
X-93617Y-257628D01*
X-91871Y-257337D01*
X-90561Y-257628D01*
X-89032Y-258795D01*
X-88377Y-260545D01*
Y-269003D01*
G01X-74589Y-251503D02*
Y-269003D01*
G01X-77646Y-257337D02*
X-71532D01*
G01X-60801Y-269003D02*
Y-257337D01*
G01Y-260253D02*
X-59927Y-258795D01*
X-58617Y-257628D01*
X-56871Y-257337D01*
X-55343Y-257628D01*
X-54032Y-258795D01*
X-53377Y-260836D01*
Y-269003D01*
G01X-39589Y-257337D02*
Y-269003D01*
G01Y-252670D02*
X-40026Y-252378D01*
Y-251795D01*
X-39589Y-251503D01*
X-39152Y-251795D01*
Y-252378D01*
X-39589Y-252670D01*
G01X-25801Y-269003D02*
Y-257337D01*
G01Y-260253D02*
X-24927Y-258795D01*
X-23617Y-257628D01*
X-21871Y-257337D01*
X-20343Y-257628D01*
X-19032Y-258795D01*
X-18377Y-260836D01*
Y-269003D01*
G01X-7646Y-273378D02*
X-6117Y-274545D01*
X-4371Y-274836D01*
X-2843Y-274545D01*
X-1532Y-273087D01*
X-659Y-271045D01*
Y-257337D01*
G01Y-259670D02*
X-1532Y-258503D01*
X-2843Y-257628D01*
X-4371Y-257337D01*
X-6117Y-257920D01*
X-7209Y-259086D01*
X-8083Y-261128D01*
X-8519Y-263170D01*
X-8301Y-264920D01*
X-7427Y-266962D01*
X-6117Y-268420D01*
X-4371Y-269003D01*
X-3061Y-268711D01*
X-1532Y-267545D01*
X-659Y-266379D01*
G01X26044Y-269003D02*
Y-251503D01*
X31284D01*
X33031Y-252378D01*
X34341Y-254420D01*
X34778Y-256753D01*
X34341Y-259086D01*
X33249Y-260836D01*
X31284Y-261712D01*
X26044D01*
G01X42452Y-251503D02*
X47911Y-269003D01*
X53370Y-251503D01*
G01X65411D02*
Y-269003D01*
G01X60389Y-251503D02*
X70433D01*
G01X94734Y-269003D02*
Y-251503D01*
X100411Y-266086D01*
X106088Y-251503D01*
Y-269003D01*
G01X117911Y-269586D02*
X117474Y-269295D01*
Y-268711D01*
X117911Y-268420D01*
X118348Y-268711D01*
Y-269295D01*
X117911Y-269586D01*
G01X131263Y-254420D02*
X132573Y-252670D01*
X134101Y-251795D01*
X135848Y-251503D01*
X138031Y-252086D01*
X139559Y-253545D01*
X139996Y-255294D01*
X139778Y-257045D01*
X138904Y-258503D01*
X134538Y-261420D01*
X132573Y-263461D01*
X131263Y-266379D01*
X130826Y-269003D01*
X139996D01*
G01X164952D02*
X170411Y-251503D01*
X175870Y-269003D01*
G01X173904Y-262878D02*
X166917D01*
G01X191841Y-251503D02*
Y-269003D01*
G01Y-266379D02*
X190968Y-267837D01*
X189657Y-268711D01*
X188129Y-269003D01*
X186383Y-268420D01*
X185073Y-266962D01*
X184199Y-265212D01*
X183981Y-263170D01*
X184199Y-261128D01*
X185073Y-259378D01*
X186383Y-257920D01*
X188129Y-257337D01*
X189657Y-257628D01*
X190749Y-258212D01*
X191841Y-259378D01*
G01X209341Y-269003D02*
Y-257337D01*
G01Y-259378D02*
X208468Y-258212D01*
X207157Y-257628D01*
X205629Y-257337D01*
X204101Y-257920D01*
X202791Y-259086D01*
X201917Y-260836D01*
X201481Y-263170D01*
X201917Y-265503D01*
X202791Y-267253D01*
X204101Y-268420D01*
X205629Y-269003D01*
X207157Y-268711D01*
X208468Y-267837D01*
X209341Y-266670D01*
G01X218981Y-274836D02*
Y-257337D01*
G01Y-259961D02*
X220073Y-258503D01*
X221164Y-257628D01*
X222911Y-257337D01*
X224439Y-257628D01*
X225968Y-259086D01*
X226623Y-261128D01*
X226841Y-263170D01*
X226623Y-265212D01*
X225968Y-267253D01*
X224657Y-268420D01*
X222911Y-269003D01*
X221383Y-268711D01*
X219854Y-267837D01*
X218981Y-266670D01*
G01X240411Y-251503D02*
Y-269003D01*
G01X237354Y-257337D02*
X243468D01*
G01X257911Y-269003D02*
X256601Y-268711D01*
X255291Y-267545D01*
X254417Y-265503D01*
X253981Y-263170D01*
X254417Y-260836D01*
X255291Y-258795D01*
X256601Y-257628D01*
X257911Y-257337D01*
X259221Y-257628D01*
X260531Y-258795D01*
X261404Y-260836D01*
X261623Y-263170D01*
X261404Y-265503D01*
X260531Y-267545D01*
X259221Y-268711D01*
X257911Y-269003D01*
G01X272354D02*
Y-257337D01*
G01Y-259670D02*
X273446Y-258503D01*
X274538Y-257628D01*
X276066Y-257337D01*
X277157Y-257628D01*
X278468Y-258503D01*
G01X315214Y-252962D02*
X313904Y-252086D01*
X312376Y-251503D01*
X310629D01*
X308664Y-252378D01*
X307136Y-253836D01*
X306044Y-255587D01*
X305171Y-258503D01*
X304952Y-261128D01*
X305389Y-263753D01*
X306044Y-265503D01*
X307354Y-267253D01*
X308883Y-268420D01*
X310411Y-269003D01*
X311939D01*
X313468Y-268420D01*
X314778Y-267545D01*
X315870Y-266379D01*
G01X331841Y-269003D02*
Y-257337D01*
G01Y-259378D02*
X330968Y-258212D01*
X329657Y-257628D01*
X328129Y-257337D01*
X326601Y-257920D01*
X325291Y-259086D01*
X324417Y-260836D01*
X323981Y-263170D01*
X324417Y-265503D01*
X325291Y-267253D01*
X326601Y-268420D01*
X328129Y-269003D01*
X329657Y-268711D01*
X330968Y-267837D01*
X331841Y-266670D01*
G01X342354Y-269003D02*
Y-257337D01*
G01Y-259670D02*
X343446Y-258503D01*
X344538Y-257628D01*
X346066Y-257337D01*
X347157Y-257628D01*
X348468Y-258503D01*
G01X366841Y-251503D02*
Y-269003D01*
G01Y-266379D02*
X365968Y-267837D01*
X364657Y-268711D01*
X363129Y-269003D01*
X361383Y-268420D01*
X360073Y-266962D01*
X359199Y-265212D01*
X358981Y-263170D01*
X359199Y-261128D01*
X360073Y-259378D01*
X361383Y-257920D01*
X363129Y-257337D01*
X364657Y-257628D01*
X365749Y-258212D01*
X366841Y-259378D01*
G01X68484Y-224003D02*
Y-206503D01*
X74161Y-221086D01*
X79838Y-206503D01*
Y-224003D01*
G01X91661D02*
X90351Y-223711D01*
X89041Y-222545D01*
X88167Y-220503D01*
X87731Y-218170D01*
X88167Y-215836D01*
X89041Y-213795D01*
X90351Y-212628D01*
X91661Y-212337D01*
X92971Y-212628D01*
X94281Y-213795D01*
X95154Y-215836D01*
X95373Y-218170D01*
X95154Y-220503D01*
X94281Y-222545D01*
X92971Y-223711D01*
X91661Y-224003D01*
G01X113091Y-206503D02*
Y-224003D01*
G01Y-221379D02*
X112218Y-222837D01*
X110907Y-223711D01*
X109379Y-224003D01*
X107633Y-223420D01*
X106323Y-221962D01*
X105449Y-220212D01*
X105231Y-218170D01*
X105449Y-216128D01*
X106323Y-214378D01*
X107633Y-212920D01*
X109379Y-212337D01*
X110907Y-212628D01*
X111999Y-213212D01*
X113091Y-214378D01*
G01X123386Y-216128D02*
X130373D01*
X129718Y-214086D01*
X128626Y-212920D01*
X127098Y-212337D01*
X125569Y-212628D01*
X124259Y-213503D01*
X123386Y-215545D01*
X122949Y-217295D01*
Y-219045D01*
X123386Y-220795D01*
X124478Y-222545D01*
X125788Y-223711D01*
X127316Y-224003D01*
X128844Y-223420D01*
X130373Y-221670D01*
G01X144161Y-224003D02*
Y-206503D01*
G01X424761Y-269003D02*
Y-251503D01*
X422141Y-255003D01*
G01Y-269003D02*
X427381D01*
G01X437458Y-266379D02*
X438767Y-267837D01*
X440296Y-268711D01*
X442261Y-269003D01*
X444226Y-268420D01*
X445754Y-267253D01*
X446846Y-265212D01*
X447064Y-262878D01*
X446628Y-260545D01*
X445536Y-259086D01*
X444007Y-257920D01*
X442479Y-257628D01*
X440951Y-257920D01*
X438986Y-259086D01*
X439641Y-251503D01*
X445536D01*
G01X459324Y-269003D02*
X459761Y-265212D01*
X460416Y-262003D01*
X461289Y-259086D01*
X462381Y-255878D01*
X464128Y-251503D01*
X455394D01*
G01X472458Y-266379D02*
X473767Y-267837D01*
X475296Y-268711D01*
X477261Y-269003D01*
X479226Y-268420D01*
X480754Y-267253D01*
X481846Y-265212D01*
X482064Y-262878D01*
X481628Y-260545D01*
X480536Y-259086D01*
X479007Y-257920D01*
X477479Y-257628D01*
X475951Y-257920D01*
X473986Y-259086D01*
X474641Y-251503D01*
X480536D01*
G01X494761D02*
X493014Y-252086D01*
X491704Y-253545D01*
X490831Y-255294D01*
X490176Y-257628D01*
X489958Y-260253D01*
X490176Y-262878D01*
X490831Y-265212D01*
X491704Y-266962D01*
X493014Y-268420D01*
X494761Y-269003D01*
X496507Y-268420D01*
X497818Y-266962D01*
X498691Y-265212D01*
X499346Y-262878D01*
X499564Y-260253D01*
X499346Y-257628D01*
X498691Y-255294D01*
X497818Y-253545D01*
X496507Y-252086D01*
X494761Y-251503D01*
G01X411644Y-224003D02*
Y-206503D01*
X416884D01*
X418631Y-207378D01*
X419941Y-209420D01*
X420378Y-211753D01*
X419941Y-214086D01*
X418849Y-215836D01*
X416884Y-216712D01*
X411644D01*
G01X438314Y-207962D02*
X437004Y-207086D01*
X435476Y-206503D01*
X433729D01*
X431764Y-207378D01*
X430236Y-208836D01*
X429144Y-210587D01*
X428271Y-213503D01*
X428052Y-216128D01*
X428489Y-218753D01*
X429144Y-220503D01*
X430454Y-222253D01*
X431983Y-223420D01*
X433511Y-224003D01*
X435039D01*
X436568Y-223420D01*
X437878Y-222545D01*
X438970Y-221379D01*
G01X452757Y-214670D02*
X453631Y-213795D01*
X454286Y-212337D01*
X454723Y-210294D01*
X454286Y-208545D01*
X453413Y-207378D01*
X451884Y-206503D01*
X445989D01*
Y-224003D01*
X453194D01*
X454723Y-222837D01*
X455596Y-221086D01*
X456033Y-219045D01*
X455596Y-217003D01*
X454286Y-215253D01*
X452757Y-214670D01*
X445989D01*
G01X461961Y-229836D02*
X475061D01*
G01X480989Y-224003D02*
Y-206503D01*
X491033Y-224003D01*
Y-206503D01*
G01X503511Y-224003D02*
X501764Y-223711D01*
X500236Y-222545D01*
X498926Y-220795D01*
X498052Y-218753D01*
X497616Y-216420D01*
Y-214086D01*
X498052Y-211753D01*
X498926Y-209711D01*
X500236Y-207962D01*
X501764Y-206795D01*
X503511Y-206503D01*
X505257Y-206795D01*
X506786Y-207962D01*
X508096Y-209711D01*
X508970Y-211753D01*
X509406Y-214086D01*
Y-216420D01*
X508970Y-218753D01*
X508096Y-220795D01*
X506786Y-222545D01*
X505257Y-223711D01*
X503511Y-224003D01*
G01X554352Y-206503D02*
X559811Y-224003D01*
X565270Y-206503D01*
G01X581678Y-224003D02*
X572944D01*
Y-206503D01*
X581678D01*
G01X578184Y-214961D02*
X572944D01*
G01X590444Y-224003D02*
Y-206503D01*
X595903D01*
X597649Y-207378D01*
X598741Y-208545D01*
X599178Y-210878D01*
X598741Y-213212D01*
X597431Y-214670D01*
X595903Y-215545D01*
X590444D01*
G01X595903D02*
X599178Y-224003D01*
G01X612311Y-224586D02*
X611874Y-224295D01*
Y-223711D01*
X612311Y-223420D01*
X612748Y-223711D01*
Y-224295D01*
X612311Y-224586D01*
G01X586061Y-269003D02*
Y-251503D01*
X583441Y-255003D01*
G01Y-269003D02*
X588681D01*
G01X687894Y-206503D02*
Y-224003D01*
X696628D01*
G01X713691D02*
Y-212337D01*
G01Y-214378D02*
X712818Y-213212D01*
X711507Y-212628D01*
X709979Y-212337D01*
X708451Y-212920D01*
X707141Y-214086D01*
X706267Y-215836D01*
X705831Y-218170D01*
X706267Y-220503D01*
X707141Y-222253D01*
X708451Y-223420D01*
X709979Y-224003D01*
X711507Y-223711D01*
X712818Y-222837D01*
X713691Y-221670D01*
G01X722676Y-229253D02*
X723986Y-229836D01*
X725733Y-229253D01*
X726824Y-228087D01*
X727698Y-226628D01*
X729007Y-221962D01*
X731846Y-212337D01*
G01X724859D02*
X729007Y-221962D01*
G01X741486Y-216128D02*
X748473D01*
X747818Y-214086D01*
X746726Y-212920D01*
X745198Y-212337D01*
X743669Y-212628D01*
X742359Y-213503D01*
X741486Y-215545D01*
X741049Y-217295D01*
Y-219045D01*
X741486Y-220795D01*
X742578Y-222545D01*
X743888Y-223711D01*
X745416Y-224003D01*
X746944Y-223420D01*
X748473Y-221670D01*
G01X759204Y-224003D02*
Y-212337D01*
G01Y-214670D02*
X760296Y-213503D01*
X761388Y-212628D01*
X762916Y-212337D01*
X764007Y-212628D01*
X765318Y-213503D01*
G01X740378Y-251503D02*
Y-269003D01*
X731644D01*
G01X718511D02*
X716983Y-268711D01*
X715236Y-267837D01*
X714144Y-266379D01*
X713708Y-264336D01*
X714144Y-262295D01*
X715454Y-260545D01*
X717419Y-259670D01*
X719603D01*
X720913Y-259086D01*
X722005Y-257628D01*
X722441Y-255587D01*
X721786Y-253545D01*
X720258Y-252086D01*
X718511Y-251503D01*
X716765Y-252086D01*
X715236Y-253545D01*
X714581Y-255587D01*
X715018Y-257628D01*
X716109Y-259086D01*
X717419Y-259670D01*
X719603D01*
X721568Y-260545D01*
X722878Y-262295D01*
X723314Y-264336D01*
X722878Y-266379D01*
X721786Y-267837D01*
X720039Y-268711D01*
X718511Y-269003D01*
G01X830008Y-224003D02*
Y-206503D01*
X834374D01*
X836121Y-207378D01*
X837431Y-208545D01*
X838523Y-210294D01*
X839396Y-212337D01*
X839614Y-215253D01*
X839396Y-218170D01*
X838523Y-220212D01*
X837431Y-221962D01*
X836121Y-223128D01*
X834374Y-224003D01*
X830008D01*
G01X849036Y-216128D02*
X856023D01*
X855368Y-214086D01*
X854276Y-212920D01*
X852748Y-212337D01*
X851219Y-212628D01*
X849909Y-213503D01*
X849036Y-215545D01*
X848599Y-217295D01*
Y-219045D01*
X849036Y-220795D01*
X850128Y-222545D01*
X851438Y-223711D01*
X852966Y-224003D01*
X854494Y-223420D01*
X856023Y-221670D01*
G01X866536Y-221962D02*
X867628Y-223128D01*
X869156Y-224003D01*
X870466D01*
X871776Y-223420D01*
X872649Y-222545D01*
X873086Y-221379D01*
X872868Y-219628D01*
X871994Y-218753D01*
X868064Y-217003D01*
X867191Y-214961D01*
X867628Y-213503D01*
X868501Y-212628D01*
X869811Y-212337D01*
X871121Y-212628D01*
X872431Y-213503D01*
G01X887311Y-212337D02*
Y-224003D01*
G01Y-207670D02*
X886874Y-207378D01*
Y-206795D01*
X887311Y-206503D01*
X887748Y-206795D01*
Y-207378D01*
X887311Y-207670D01*
G01X901754Y-228378D02*
X903283Y-229545D01*
X905029Y-229836D01*
X906557Y-229545D01*
X907868Y-228087D01*
X908741Y-226045D01*
Y-212337D01*
G01Y-214670D02*
X907868Y-213503D01*
X906557Y-212628D01*
X905029Y-212337D01*
X903283Y-212920D01*
X902191Y-214086D01*
X901317Y-216128D01*
X900881Y-218170D01*
X901099Y-219920D01*
X901973Y-221962D01*
X903283Y-223420D01*
X905029Y-224003D01*
X906339Y-223711D01*
X907868Y-222545D01*
X908741Y-221379D01*
G01X918599Y-224003D02*
Y-212337D01*
G01Y-215253D02*
X919473Y-213795D01*
X920783Y-212628D01*
X922529Y-212337D01*
X924057Y-212628D01*
X925368Y-213795D01*
X926023Y-215836D01*
Y-224003D01*
G01X936536Y-216128D02*
X943523D01*
X942868Y-214086D01*
X941776Y-212920D01*
X940248Y-212337D01*
X938719Y-212628D01*
X937409Y-213503D01*
X936536Y-215545D01*
X936099Y-217295D01*
Y-219045D01*
X936536Y-220795D01*
X937628Y-222545D01*
X938938Y-223711D01*
X940466Y-224003D01*
X941994Y-223420D01*
X943523Y-221670D01*
G01X954254Y-224003D02*
Y-212337D01*
G01Y-214670D02*
X955346Y-213503D01*
X956438Y-212628D01*
X957966Y-212337D01*
X959057Y-212628D01*
X960368Y-213503D01*
G01X874194Y-265503D02*
X875286Y-267253D01*
X876596Y-268420D01*
X878124Y-269003D01*
X879871Y-268420D01*
X881181Y-267253D01*
X882491Y-265503D01*
X882928Y-263170D01*
Y-251503D01*
G01X896061Y-269003D02*
X894314Y-268711D01*
X892786Y-267545D01*
X891476Y-265795D01*
X890602Y-263753D01*
X890166Y-261420D01*
Y-259086D01*
X890602Y-256753D01*
X891476Y-254711D01*
X892786Y-252962D01*
X894314Y-251795D01*
X896061Y-251503D01*
X897807Y-251795D01*
X899336Y-252962D01*
X900646Y-254711D01*
X901520Y-256753D01*
X901956Y-259086D01*
Y-261420D01*
X901520Y-263753D01*
X900646Y-265795D01*
X899336Y-267545D01*
X897807Y-268711D01*
X896061Y-269003D01*
G01X913561D02*
Y-261128D01*
X909194Y-251503D01*
G01X917928D02*
X913561Y-261128D01*
G01X1001011Y-269003D02*
Y-251503D01*
X998391Y-255003D01*
G01Y-269003D02*
X1003631D01*
G01X1014363Y-254420D02*
X1015673Y-252670D01*
X1017201Y-251795D01*
X1018948Y-251503D01*
X1021131Y-252086D01*
X1022659Y-253545D01*
X1023096Y-255294D01*
X1022878Y-257045D01*
X1022004Y-258503D01*
X1017638Y-261420D01*
X1015673Y-263461D01*
X1014363Y-266379D01*
X1013926Y-269003D01*
X1023096D01*
G01X1032081Y-269586D02*
X1039941Y-251503D01*
G01X1048708Y-265503D02*
X1050017Y-267545D01*
X1051764Y-268711D01*
X1053729Y-269003D01*
X1055476Y-268711D01*
X1057223Y-267253D01*
X1058314Y-265503D01*
X1058533Y-263753D01*
X1058096Y-261712D01*
X1056568Y-260253D01*
X1055039Y-259670D01*
X1053074D01*
G01X1055039D02*
X1056349Y-258795D01*
X1057441Y-257337D01*
X1057878Y-255587D01*
X1057441Y-253836D01*
X1056349Y-252378D01*
X1054384Y-251503D01*
X1052419Y-251795D01*
X1050454Y-252962D01*
G01X1071011Y-251503D02*
X1069264Y-252086D01*
X1067954Y-253545D01*
X1067081Y-255294D01*
X1066426Y-257628D01*
X1066208Y-260253D01*
X1066426Y-262878D01*
X1067081Y-265212D01*
X1067954Y-266962D01*
X1069264Y-268420D01*
X1071011Y-269003D01*
X1072757Y-268420D01*
X1074068Y-266962D01*
X1074941Y-265212D01*
X1075596Y-262878D01*
X1075814Y-260253D01*
X1075596Y-257628D01*
X1074941Y-255294D01*
X1074068Y-253545D01*
X1072757Y-252086D01*
X1071011Y-251503D01*
G01X1084581Y-269586D02*
X1092441Y-251503D01*
G01X1101863Y-254420D02*
X1103173Y-252670D01*
X1104701Y-251795D01*
X1106448Y-251503D01*
X1108631Y-252086D01*
X1110159Y-253545D01*
X1110596Y-255294D01*
X1110378Y-257045D01*
X1109504Y-258503D01*
X1105138Y-261420D01*
X1103173Y-263461D01*
X1101863Y-266379D01*
X1101426Y-269003D01*
X1110596D01*
G01X1123511Y-251503D02*
X1121764Y-252086D01*
X1120454Y-253545D01*
X1119581Y-255294D01*
X1118926Y-257628D01*
X1118708Y-260253D01*
X1118926Y-262878D01*
X1119581Y-265212D01*
X1120454Y-266962D01*
X1121764Y-268420D01*
X1123511Y-269003D01*
X1125257Y-268420D01*
X1126568Y-266962D01*
X1127441Y-265212D01*
X1128096Y-262878D01*
X1128314Y-260253D01*
X1128096Y-257628D01*
X1127441Y-255294D01*
X1126568Y-253545D01*
X1125257Y-252086D01*
X1123511Y-251503D01*
G01X1141011Y-269003D02*
Y-251503D01*
X1138391Y-255003D01*
G01Y-269003D02*
X1143631D01*
G01X1154363Y-261712D02*
X1155891Y-259670D01*
X1157201Y-258503D01*
X1158948Y-257920D01*
X1160476Y-258503D01*
X1161568Y-259670D01*
X1162441Y-261420D01*
X1162659Y-263461D01*
X1162441Y-265212D01*
X1161568Y-266962D01*
X1160257Y-268420D01*
X1158729Y-269003D01*
X1156983Y-268420D01*
X1155454Y-266670D01*
X1154581Y-264045D01*
X1154363Y-261128D01*
X1154799Y-257337D01*
X1155454Y-255294D01*
X1156546Y-253253D01*
X1158074Y-251795D01*
X1159603Y-251503D01*
X1161131Y-252086D01*
X1162223Y-253545D01*
G01X1048708Y-224003D02*
Y-206503D01*
X1053074D01*
X1054821Y-207378D01*
X1056131Y-208545D01*
X1057223Y-210294D01*
X1058096Y-212337D01*
X1058314Y-215253D01*
X1058096Y-218170D01*
X1057223Y-220212D01*
X1056131Y-221962D01*
X1054821Y-223128D01*
X1053074Y-224003D01*
X1048708D01*
G01X1074941D02*
Y-212337D01*
G01Y-214378D02*
X1074068Y-213212D01*
X1072757Y-212628D01*
X1071229Y-212337D01*
X1069701Y-212920D01*
X1068391Y-214086D01*
X1067517Y-215836D01*
X1067081Y-218170D01*
X1067517Y-220503D01*
X1068391Y-222253D01*
X1069701Y-223420D01*
X1071229Y-224003D01*
X1072757Y-223711D01*
X1074068Y-222837D01*
X1074941Y-221670D01*
G01X1088511Y-206503D02*
Y-224003D01*
G01X1085454Y-212337D02*
X1091568D01*
G01X1102736Y-216128D02*
X1109723D01*
X1109068Y-214086D01*
X1107976Y-212920D01*
X1106448Y-212337D01*
X1104919Y-212628D01*
X1103609Y-213503D01*
X1102736Y-215545D01*
X1102299Y-217295D01*
Y-219045D01*
X1102736Y-220795D01*
X1103828Y-222545D01*
X1105138Y-223711D01*
X1106666Y-224003D01*
X1108194Y-223420D01*
X1109723Y-221670D01*
G54D23*
X119800Y293000D03*
X205800Y309500D03*
X254800Y88500D03*
X245300Y156500D03*
Y152500D03*
X254800Y197000D03*
G54D32*
X255200Y164500D03*
G54D14*
X62500Y279500D03*
X67050Y338239D03*
X96400Y292250D03*
X100250Y324750D03*
X122500Y296600D03*
X112500Y302000D03*
X120750Y324544D03*
X107300Y317000D03*
X118500Y318500D03*
X111400Y311750D03*
X109500Y330500D03*
X119500Y330000D03*
X135000Y293000D03*
X136500Y311500D03*
X139500Y321000D03*
X125100Y340250D03*
X161311Y302000D03*
X165811Y308000D03*
X163500Y313300D03*
X181061Y302000D03*
X177811Y309500D03*
X173811Y324500D03*
Y315000D03*
X195561Y304250D03*
X202911Y296500D03*
X237500Y92000D03*
X239500Y43500D03*
X249000Y65000D03*
X252000Y82338D03*
X252500Y103000D03*
X249000Y132500D03*
X254500Y148500D03*
X255500Y153500D03*
X240500Y150000D03*
X240437Y161999D03*
X240300Y168500D03*
X252000Y191000D03*
X249000Y185000D03*
X252500Y211500D03*
X249000Y241000D03*
X244000Y277500D03*
X259500Y82338D03*
X257000Y92500D03*
X256500Y100000D03*
Y106000D03*
X267000Y131693D03*
X259500Y191000D03*
X256500Y208500D03*
Y201000D03*
Y214500D03*
X266500Y244000D03*
X263000Y318500D03*
X284000Y107392D03*
X274750Y140500D03*
X283000Y143000D03*
X284662Y170000D03*
X287500Y186500D03*
X276500Y197000D03*
X295311Y123500D03*
X290500Y139875D03*
X294000Y166500D03*
X316500Y249500D03*
Y320500D03*
G54D42*
G01X302800Y137043D02*
G03X304622Y135422I1822J213D01*
G01X304718D01*
G03X305920Y135920I0J1700D01*
G02X307122Y136418I1202J-1202D01*
G01X310118D01*
G01X302800Y132643D02*
G02X304622Y134264I1822J-213D01*
G01X304632D01*
G02X305834Y133766I0J-1700D01*
G03X307036Y133268I1202J1202D01*
G01X310118D01*
G01X320394Y62500D02*
X325244D01*
G01X320394Y59351D02*
X325244D01*
G01X320394Y78248D02*
X325244D01*
G01X320394Y68799D02*
X325244D01*
G01X320394Y71949D02*
X325244D01*
G01X320394Y87697D02*
X325244D01*
G01X320394Y90847D02*
X325244D01*
G01X320394Y81398D02*
X325244D01*
G01X320394Y106595D02*
X325244D01*
G01X320394Y109744D02*
X325244D01*
G01X320394Y100296D02*
X325244D01*
G01X320394Y97146D02*
X325244D01*
G01X320394Y156988D02*
X325244D01*
G01X320394Y160138D02*
X325244D01*
G01X320394Y150689D02*
X325244D01*
G01X320394Y147540D02*
X325244D01*
G01Y166437D02*
X320394D01*
G01X325244Y169587D02*
X320394D01*
G54D24*
X155811Y305700D03*
Y313300D03*
G54D33*
X270940Y162250D03*
Y155750D03*
X273500Y162250D03*
X276060D03*
Y155750D03*
G54D15*
G01X-176139Y-183003D02*
G02I-12000J0D01*
G01X-181289D02*
G02I-6850J0D01*
G01X-172139D02*
X-204139D01*
G01X-188139Y-199003D02*
Y-167003D01*
G01X-172139Y-199003D02*
Y-279003D01*
G01D02*
X1178561D01*
G01X-172139Y-234503D02*
X1178561D01*
G01X-172139Y-199003D02*
X1178561D01*
G01X8444Y316176D02*
X25596D01*
G01Y299024D02*
Y316176D01*
G01D02*
Y333328D01*
G01Y316176D02*
X42748D01*
G01X119750Y293000D02*
X110526D01*
X109326Y291800D01*
X106674D01*
X102724Y295750D01*
X100000D01*
G01X99000Y284250D02*
X95000D01*
G01X99000D02*
X99872D01*
X101622Y282500D01*
X107378D01*
X109128Y284250D01*
X110000D01*
G01X96750Y321000D02*
Y317000D01*
G01D02*
Y313250D01*
G01Y328500D02*
Y343539D01*
X100500Y347289D01*
G01X109000Y341250D02*
X106539D01*
X100500Y347289D01*
G01X121456Y289154D02*
X119750Y290860D01*
Y293000D01*
G01X125000Y277000D02*
X125300Y277300D01*
Y282200D01*
X123250Y284250D01*
X114000D01*
G01D02*
Y287500D01*
X112500Y289000D01*
G01X110000Y284250D02*
X114000D01*
G01X115000Y308250D02*
Y305000D01*
G01X119000Y308250D02*
X115000D01*
G01X113500Y341250D02*
X117500D01*
G01X109000D02*
X113500D01*
G01X121500D02*
X117500D01*
G01X155811Y305700D02*
X155000Y304889D01*
Y301350D01*
G01X163500Y313300D02*
X155811D01*
G01D02*
X149511D01*
X149311Y313500D01*
G01X161311Y302000D02*
X164811Y298500D01*
Y296000D01*
X166811Y294000D01*
X176311D01*
G01X209250Y309500D02*
Y297747D01*
X198903Y287400D01*
X163244D01*
X159011Y291633D01*
Y299700D01*
X161311Y302000D01*
G01X160811Y310000D02*
X161311Y309500D01*
Y302000D01*
G01X168311Y298250D02*
X172311D01*
G01D02*
X176311D01*
G01X163500Y313300D02*
X169611D01*
X169811Y313500D01*
G01X181061Y302000D02*
Y297750D01*
G01D02*
X180561Y298250D01*
X176311D01*
G01X193561Y317000D02*
Y310000D01*
X191061Y307500D01*
X185292D01*
X181061Y303269D01*
Y302000D01*
G01X199811Y300750D02*
X195811Y296750D01*
Y296000D01*
G01X204811Y314000D02*
X200811D01*
G01X219861Y17712D02*
X237013D01*
G01X210811Y314000D02*
X208000Y316811D01*
Y320000D01*
G01X214000D02*
Y317164D01*
X215064Y316100D01*
G01X237013Y17712D02*
Y34864D01*
G01Y17712D02*
X254165D01*
G01X254750Y96500D02*
X230000D01*
G01X229311Y160250D02*
X225000D01*
G01X229311Y149250D02*
X225000D01*
G01X233311Y160250D02*
Y164250D01*
G01Y149250D02*
X235250D01*
X237000Y151000D01*
Y152500D01*
G01X229311Y164250D02*
X225000D01*
G01X237000D02*
X233311D01*
G01X254750Y205000D02*
X225000D01*
G01X254750Y88500D02*
X251000D01*
G01X255250Y164500D02*
X251500D01*
G01X254750Y197000D02*
X251000D01*
G01X271250Y135500D02*
Y138750D01*
G01X264500Y153250D02*
X267700D01*
G01X268140Y161221D02*
X268111Y161250D01*
X264500D01*
G01Y156750D02*
Y161250D01*
G01X258750Y160500D02*
Y164500D01*
G01D02*
Y168000D01*
G01X270500Y240250D02*
X273600D01*
G01X270255Y345704D02*
X287407D01*
G01X282500Y164750D02*
X281250Y166000D01*
X279000D01*
G01X287407Y328552D02*
Y345704D01*
G01D02*
X304559D01*
G01X310315Y61142D02*
X304565D01*
G01X310315Y96142D02*
X304565D01*
G01X310315Y91142D02*
X305358D01*
X304500Y92000D01*
G01X290500Y139875D02*
Y127500D01*
X292000Y126000D01*
G01X310118Y130119D02*
X306119D01*
X301000Y125000D01*
G01X310315Y141142D02*
X304565D01*
G01X290500Y150750D02*
Y139875D01*
G01X310315Y156142D02*
X303358D01*
X302000Y157500D01*
G01Y306298D02*
Y310500D01*
G01D02*
Y314702D01*
G01X297798Y310500D02*
X302000D01*
G01D02*
X306202D01*
G01X320394Y56201D02*
X325244D01*
G01X320394Y75099D02*
X325244D01*
G01X320394Y65650D02*
X325244D01*
G01X320394Y93996D02*
X325244D01*
G01X320394Y84548D02*
X325244D01*
G01X320394Y112894D02*
X325244D01*
G01X320394Y103445D02*
X325244D01*
G01X320394Y128642D02*
X325244D01*
G01X320394Y119193D02*
X325244D01*
G01X320394Y144390D02*
X325244D01*
G01X320394Y138091D02*
X325244D01*
G01X320394Y153839D02*
X325244D01*
G01X310315Y171142D02*
Y176815D01*
X313000Y179500D01*
G01X320394Y163288D02*
X325244D01*
G01X391061Y-199003D02*
Y-279003D01*
G01X528561Y-199003D02*
Y-279003D01*
G01X643561Y-199003D02*
Y-279003D01*
G01X811061Y-199003D02*
Y-279003D01*
G01X981061Y-199003D02*
Y-279003D01*
G01X1178561Y-199003D02*
Y-279003D01*
G01X1210561Y-183003D02*
X1178561D01*
G01X1206561D02*
G02I-12000J0D01*
G01X1201411D02*
G02I-6850J0D01*
G01X1194561Y-199003D02*
Y-167003D01*
X103000Y277500D03*
X95000D03*
X99000D03*
X106500D03*
X92500Y295000D03*
X106137Y286000D03*
X100000Y288500D03*
X92500Y298500D03*
Y309000D03*
X107000Y311500D03*
Y308000D03*
X96750Y313250D03*
X103750Y313200D03*
X100250D03*
X103500Y317000D03*
Y321000D03*
X91500Y312500D03*
X100500Y335689D03*
X96750Y328500D03*
X100500Y347289D03*
X121500Y276500D03*
X118000D03*
X114500D03*
X110500Y277500D03*
X121456Y289154D03*
X122100Y280750D03*
X112500Y289000D03*
X108000Y295000D03*
X122000Y301000D03*
X108000Y298500D03*
X115000Y305000D03*
X119000D03*
X108000Y303100D03*
X120120Y315000D03*
X116500D03*
X109500Y334500D03*
X113000D03*
X117000D03*
X121000D03*
X125000Y277000D03*
X128500Y282500D03*
X126000Y287000D03*
X130000Y298500D03*
X124000Y315000D03*
X140500Y281000D03*
X215064Y316100D03*
X236805Y146452D03*
X225000Y160250D03*
Y149250D03*
X237000Y156000D03*
Y159780D03*
Y152500D03*
X225000Y164250D03*
X236500Y168500D03*
X225000Y169500D03*
X237000Y164250D03*
X251000Y88500D03*
X252000Y151500D03*
Y155000D03*
Y160500D03*
X251500Y164500D03*
X251000Y197000D03*
X263000Y96500D03*
Y88500D03*
Y81338D03*
Y84838D03*
X269650Y97899D03*
X271650Y109710D03*
X269650Y102299D03*
X263000Y104000D03*
X262819Y100157D03*
X271650Y114110D03*
X271250Y138750D03*
X267700Y153250D03*
X268140Y161221D03*
X258750Y168000D03*
X263000Y190000D03*
Y193500D03*
X269650Y210961D03*
Y206561D03*
X263000Y205000D03*
Y197000D03*
Y212500D03*
X262819Y208819D03*
X271650Y222772D03*
Y218372D03*
X263000Y240315D03*
X275100Y109710D03*
X273100Y102299D03*
Y97899D03*
X275100Y114110D03*
X278860Y162250D03*
X279000Y166000D03*
X273500Y194055D03*
Y199961D03*
X273100Y210961D03*
Y206561D03*
X275100Y222772D03*
Y218372D03*
X273600Y240250D03*
X295000Y86699D03*
Y89899D03*
X300500Y129100D03*
X301000Y125000D03*
X292000Y126000D03*
X299300Y137043D03*
Y132643D03*
X302800Y137043D03*
Y132643D03*
X290500Y154250D03*
X296500Y157500D03*
X302000D03*
X290500Y150750D03*
X291000Y169500D03*
X292000Y181500D03*
X294750Y195261D03*
X291300Y195361D03*
X294750Y198661D03*
X291300Y198561D03*
X325244Y49902D03*
Y53051D03*
Y56201D03*
Y62500D03*
Y59351D03*
Y75099D03*
Y65650D03*
Y78248D03*
Y68799D03*
Y71949D03*
Y93996D03*
Y84548D03*
Y97146D03*
Y87697D03*
Y90847D03*
Y81398D03*
Y112894D03*
Y103445D03*
Y106595D03*
Y109744D03*
Y100296D03*
Y128642D03*
Y119193D03*
Y144390D03*
Y138091D03*
Y153839D03*
Y156988D03*
Y160138D03*
Y150689D03*
Y147540D03*
Y163288D03*
Y166437D03*
Y169587D03*
G54D43*
G01X95000Y280750D02*
Y277500D01*
G01X99000Y280750D02*
Y277500D01*
G01X100000Y292250D02*
Y288500D01*
G01Y292250D02*
X96400D01*
G01X96500Y302250D02*
Y299000D01*
X92500Y295000D01*
G01X91500Y312500D02*
X92500D01*
X96500Y308500D01*
Y305750D01*
G01X92500Y302250D02*
Y298500D01*
G01Y305750D02*
Y309000D01*
G01X100500Y302250D02*
X100750D01*
X108000Y295000D01*
G01X100500Y305750D02*
X101250D01*
X107000Y311500D01*
G01X104500Y302250D02*
Y302000D01*
X108000Y298500D01*
G01X104500Y305750D02*
X104750D01*
X107000Y308000D01*
G01X100250Y317000D02*
X103500D01*
G01D02*
X107300D01*
G01X100250Y321000D02*
X103500D01*
G01X100250D02*
Y324750D01*
G01X121500Y276500D02*
X123939Y274061D01*
X217122D01*
X226212Y264971D01*
Y230699D01*
X242411Y214500D01*
X256500D01*
G01X118000Y276500D02*
X122414Y272086D01*
X216303D01*
X224237Y264152D01*
Y229880D01*
X242617Y211500D01*
X252500D01*
G01X114500Y276500D02*
Y276294D01*
X120683Y270111D01*
X215484D01*
X222262Y263333D01*
Y126149D01*
X242411Y106000D01*
X256500D01*
G01X106500Y277500D02*
X109750Y280750D01*
X110000D01*
G01X114000D02*
X113750D01*
X110500Y277500D01*
G01D02*
Y276000D01*
X118364Y268136D01*
X214665D01*
X220287Y262514D01*
Y125330D01*
X242617Y103000D01*
X252500D01*
G01X108000Y303100D02*
X109100Y302000D01*
X112500D01*
G01D02*
X116000D01*
X119000Y305000D01*
G01X109500Y330500D02*
X118294Y321706D01*
X120794D01*
X126000Y316500D01*
Y316448D01*
X126438Y316010D01*
Y313990D01*
X125500Y313052D01*
Y293867D01*
X126213Y293154D01*
Y290235D01*
X128438Y288010D01*
Y286010D01*
X138412Y276036D01*
X217941D01*
X231439Y262538D01*
X250051D01*
X254587Y258002D01*
Y224361D01*
X265538Y213410D01*
Y184832D01*
X243275Y162569D01*
Y154475D01*
X245250Y152500D01*
G01Y156500D02*
Y161750D01*
X267513Y184013D01*
Y214229D01*
X256562Y225180D01*
Y258821D01*
X250870Y264513D01*
X232258D01*
X218760Y278011D01*
X139231D01*
X130414Y286828D01*
Y288828D01*
X128188Y291054D01*
Y295842D01*
X127475Y296555D01*
Y312233D01*
X128413Y313171D01*
Y316829D01*
X127975Y317267D01*
Y317319D01*
X120750Y324544D01*
G01X113000Y334500D02*
Y332294D01*
X120750Y324544D01*
G01X119000Y311750D02*
Y313880D01*
X120120Y315000D01*
G01D02*
Y316880D01*
X118500Y318500D01*
G01X115000Y311750D02*
Y313500D01*
X116500Y315000D01*
G01X115000Y311750D02*
X111400D01*
G01X109500Y334500D02*
Y337250D01*
X109000Y337750D01*
G01X109500Y330500D02*
Y334500D01*
G01X113500Y337750D02*
X113000Y337250D01*
Y334500D01*
G01X117500Y337750D02*
X117000Y337250D01*
Y334500D01*
G01D02*
Y332500D01*
X119500Y330000D01*
G01X121500Y337750D02*
X122600D01*
X125100Y340250D01*
G01X121500Y337750D02*
Y335000D01*
X121000Y334500D01*
G01X123250Y293000D02*
Y292880D01*
X124238Y291892D01*
Y289416D01*
X126000Y287654D01*
Y287000D01*
G01X123250Y293000D02*
Y295850D01*
X122500Y296600D01*
G01X229311Y152750D02*
X233311D01*
G01D02*
X233750D01*
X237000Y156000D01*
G01X240500Y150000D02*
Y152500D01*
X237000Y156000D01*
G01X229311Y156750D02*
X233311D01*
G01X240437Y161999D02*
X239219D01*
X237000Y159780D01*
G01X233311Y156750D02*
X233970D01*
X237000Y159780D01*
G01X229311Y167750D02*
X233311D01*
G01X236500Y168500D02*
X235750Y167750D01*
X233311D01*
G01X240300Y168500D02*
X236500D01*
G01X263000Y81338D02*
X261862Y80200D01*
X254138D01*
X252000Y82338D01*
G01X252500Y103000D02*
X259976D01*
X262819Y100157D01*
G01X296500Y61000D02*
X265438Y92062D01*
Y105010D01*
X257500Y112948D01*
Y140250D01*
X245250Y152500D01*
G01Y156500D02*
X247225Y158475D01*
X250577D01*
X251614Y157438D01*
X255575D01*
X258338Y154675D01*
Y142206D01*
X259475Y141069D01*
Y113767D01*
X267413Y105829D01*
Y94087D01*
X300500Y61000D01*
G01X248750Y152500D02*
X251000D01*
X252000Y151500D01*
G01X254500Y148500D02*
Y149000D01*
X252000Y151500D01*
G01X248750Y156500D02*
X249923Y155327D01*
X251673D01*
X252000Y155000D01*
G01X255500Y153500D02*
X253500D01*
X252000Y155000D01*
G01X255250Y160500D02*
X252000D01*
G01Y191000D02*
X254138Y188862D01*
X261862D01*
X263000Y190000D01*
G01X252500Y211500D02*
X260138D01*
X262819Y208819D01*
G01X258250Y88500D02*
X263000D01*
G01X258250D02*
Y91250D01*
X257000Y92500D01*
G01X259500Y82338D02*
X260500D01*
X263000Y84838D01*
G01X258250Y96500D02*
X263000D01*
G01X258250D02*
Y98250D01*
X256500Y100000D01*
G01Y106000D02*
X261000D01*
X263000Y104000D01*
G01X264500Y164750D02*
X264128D01*
X261762Y162384D01*
Y152116D01*
X263366Y150512D01*
X264738D01*
X274750Y140500D01*
G01X267000Y131693D02*
X262960D01*
X262920Y131653D01*
G01X271250Y131500D02*
X271057Y131693D01*
X267000D01*
G01X270940Y162250D02*
Y160567D01*
X272395Y159112D01*
X280362D01*
X282500Y161250D01*
G01X264500Y164750D02*
X265138Y165388D01*
X272045D01*
X273500Y163933D01*
Y162250D01*
G01X259500Y191000D02*
X260500D01*
X263000Y193500D01*
G01X258250Y205000D02*
X263000D01*
G01X258250D02*
Y206750D01*
X256500Y208500D01*
G01Y201000D02*
X258250Y199250D01*
Y197000D01*
G01D02*
X263000D01*
G01Y212500D02*
X261000Y214500D01*
X256500D01*
G01X270500Y236750D02*
X266500D01*
G01X284662Y170000D02*
Y222588D01*
X270500Y236750D01*
G01X266500Y240250D02*
X263065D01*
X263000Y240315D01*
G01X266500Y240250D02*
Y244000D01*
G01X273000Y92283D02*
X284000Y103283D01*
Y107392D01*
G01D02*
X292892D01*
X295500Y110000D01*
G01X283000Y143000D02*
Y131127D01*
X300000Y114127D01*
Y74501D01*
X301500Y73000D01*
X308358Y66142D01*
X310315D01*
G01X274750Y131500D02*
Y135500D01*
G01D02*
Y140500D01*
G01X276060Y155750D02*
Y154440D01*
X283000Y147500D01*
Y143000D01*
G01X282500Y161250D02*
X283261Y162011D01*
X283633D01*
X285238Y163616D01*
Y165885D01*
X284662Y166461D01*
Y170000D01*
G01X310315Y71142D02*
X305727D01*
X301675Y75195D01*
Y104967D01*
G01D02*
Y117563D01*
X298149Y121089D01*
Y128351D01*
X296500Y130000D01*
Y154052D01*
X298938Y156490D01*
Y161562D01*
X294000Y166500D01*
G01X310315Y101142D02*
X305500D01*
X301675Y104967D01*
G01X295311Y127600D02*
X294825Y128086D01*
Y155825D01*
X296500Y157500D01*
G01X295311Y123500D02*
Y127600D01*
G01X287500Y186500D02*
Y166908D01*
X290500Y163908D01*
Y154250D01*
G01X294000Y166500D02*
X291000Y169500D01*
G01X301711Y245000D02*
X290967D01*
X287500Y241533D01*
Y186500D01*
G01X320394Y49902D02*
X325244D01*
G01X320394Y53051D02*
X325244D01*
G01X304500Y123820D02*
X310118D01*
G01Y126969D02*
X307649D01*
X304500Y123820D01*
G54D34*
X258800Y164500D03*
G54D25*
X143511Y313500D03*
X205011Y314000D03*
G54D16*
X99000Y284200D03*
X95000D03*
X110000D03*
X114000D03*
X117500Y341200D03*
X121500D03*
X168311Y301700D03*
X172311D03*
X176311D03*
X199811Y304200D03*
X233311Y152700D03*
X229311Y160200D03*
X233311Y167700D03*
X264500Y164700D03*
X266500Y240200D03*
X270500D03*
G54D17*
X99000Y280800D03*
X95000D03*
X110000D03*
X114000D03*
X117500Y337800D03*
X121500D03*
X168311Y298300D03*
X172311D03*
X176311D03*
X199811Y300800D03*
X233311Y149300D03*
X229311Y156800D03*
X233311Y164300D03*
X264500Y161300D03*
X266500Y236800D03*
X270500D03*
G54D35*
X302000Y290500D03*
Y300500D03*
Y310500D03*
G54D26*
X149111Y313500D03*
X210611Y314000D03*
G54D18*
X100000Y292300D03*
X100500Y302300D03*
X96500D03*
X104500D03*
X92500D03*
X119000Y308300D03*
X115000D03*
X109000Y337800D03*
X113500D03*
X218311Y304300D03*
X233311Y156800D03*
X229311Y149300D03*
Y164300D03*
X282500Y161300D03*
G54D36*
X320394Y46752D03*
Y49902D03*
Y53051D03*
Y56201D03*
Y59351D03*
Y62500D03*
Y65650D03*
Y68799D03*
Y71949D03*
Y75099D03*
Y78248D03*
Y81398D03*
Y84548D03*
Y87697D03*
Y90847D03*
Y93996D03*
Y97146D03*
Y100296D03*
Y103445D03*
Y106595D03*
Y109744D03*
Y112894D03*
Y116044D03*
Y119193D03*
Y122343D03*
Y125492D03*
Y128642D03*
X310118Y120670D03*
Y123820D03*
Y126969D03*
X320394Y131792D03*
Y134941D03*
Y138091D03*
Y141240D03*
Y144390D03*
X310118Y130119D03*
Y133268D03*
Y136418D03*
X320394Y147540D03*
Y150689D03*
Y153839D03*
Y156988D03*
Y160138D03*
Y163288D03*
Y166437D03*
Y169587D03*
G54D27*
X222311Y307800D03*
X264500Y156800D03*
G54D37*
X310315Y46142D03*
Y51142D03*
Y56142D03*
Y61142D03*
Y66142D03*
Y71142D03*
Y76142D03*
Y81142D03*
Y86142D03*
Y91142D03*
Y96142D03*
Y101142D03*
Y106142D03*
Y111142D03*
Y116142D03*
Y141142D03*
Y146142D03*
Y151142D03*
Y156142D03*
Y161142D03*
Y166142D03*
Y171142D03*
G54D28*
X222311Y304200D03*
X264500Y153200D03*
G54D19*
X100000Y295700D03*
X100500Y305700D03*
X96500D03*
X104500D03*
X92500D03*
X119000Y311700D03*
X115000D03*
X109000Y341200D03*
X113500D03*
X218311Y307700D03*
X233311Y160200D03*
X229311Y152700D03*
Y167700D03*
X282500Y164700D03*
G54D38*
X334252Y13307D03*
Y203977D03*
G54D29*
X213800Y320000D03*
G54D39*
G01X278860Y162250D02*
X276060D01*
M02*
